(kicad_pcb
	(version 20260206)
	(generator "pcbnew")
	(generator_version "10.0")
	(general
		(thickness 1.6)
		(legacy_teardrops no)
	)
	(paper "A4")
	(title_block
		(title "panther-plus-userver — 13130-1b_20150205.brd")
		(comment 1 "Honey Badger (Wiwynn) / footprints 1178-1186 of 1509")
	)
	(layers
		(0 "F.Cu" signal "TOP")
		(4 "In1.Cu" signal "L2")
		(6 "In2.Cu" signal "L3")
		(8 "In3.Cu" signal "L4")
		(10 "In4.Cu" signal "L5")
		(12 "In5.Cu" signal "L6")
		(14 "In6.Cu" signal "L7")
		(16 "In7.Cu" signal "L8")
		(18 "In8.Cu" signal "L9")
		(20 "In9.Cu" signal "L10")
		(22 "In10.Cu" signal "L11")
		(2 "B.Cu" signal "BOTTOM")
		(9 "F.Adhes" user "F.Adhesive")
		(11 "B.Adhes" user "B.Adhesive")
		(13 "F.Paste" user "Package Geometry/Pastemask Top")
		(15 "B.Paste" user "Package Geometry/Pastemask Bottom")
		(5 "F.SilkS" user "Ref Des/Silkscreen Top")
		(7 "B.SilkS" user "Ref Des/Silkscreen Bottom")
		(1 "F.Mask" user "Board Geometry/Soldermask Top")
		(3 "B.Mask" user "Board Geometry/Soldermask Bottom")
		(17 "Dwgs.User" user "User.Drawings")
		(19 "Cmts.User" user "User.Comments")
		(21 "Eco1.User" user "User.Eco1")
		(23 "Eco2.User" user "User.Eco2")
		(25 "Edge.Cuts" user "Board Geometry/Outline")
		(27 "Margin" user)
		(31 "F.CrtYd" user "Package Geometry/Place Bound Top")
		(29 "B.CrtYd" user "Package Geometry/Place Bound Bottom")
		(35 "F.Fab" user "Ref Des/Assembly Top")
		(33 "B.Fab" user "Ref Des/Assembly Bottom")
	)
	(footprint ""
		(layer "B.Cu")
		(at 88.138 -15.113)
		(property "Reference" "PC201"
			(at 0 0 0)
			(layer "B.SilkS")
			(hide yes)
			(effects
				(font
					(size 1.27 1.27)
				)
				(justify mirror)
			)
		)
		(property "Value" "SC10U6D3V5KX-4GP"
			(at 0.0762 -6.1214 0)
			(unlocked yes)
			(layer "B.Fab")
			(hide yes)
			(effects
				(font
					(size 1.016 1.016)
					(thickness 0.1524)
				)
				(justify mirror)
			)
		)
		(property "Device Type" "C805H58"
			(at 0.0762 -8.1534 0)
			(unlocked yes)
			(layer "B.Fab")
			(hide yes)
			(effects
				(font
					(size 1.016 1.016)
					(thickness 0.1524)
				)
				(justify mirror)
			)
		)
		(duplicate_pad_numbers_are_jumpers no)
		(fp_line
			(start -0.6096 0)
			(end 0.6096 0)
			(stroke
				(width 0.3048)
				(type default)
			)
			(layer "B.SilkS")
		)
		(fp_poly
			(pts
				(xy 0.9017 1.4351) (xy -0.9017 1.4351) (xy -0.9017 -1.4351) (xy 0.9017 -1.4351)
			)
			(stroke
				(width 0)
				(type default)
			)
			(fill no)
			(layer "B.CrtYd")
		)
		(fp_poly
			(pts
				(xy -0.9017 1.4351) (xy -0.9017 -1.4351) (xy 0.9017 -1.4351) (xy 0.9017 1.4351)
			)
			(stroke
				(width 0)
				(type default)
			)
			(fill no)
			(layer "B.Fab")
		)
		(pad "1" smd rect
			(at 0 -0.8382 180)
			(size 1.5494 0.9398)
			(layers "B.Cu" "B.Mask" "B.Paste")
			(net "TPS74801_1V35_OUT")
		)
		(pad "2" smd rect
			(at 0 0.8382 180)
			(size 1.5494 0.9398)
			(layers "B.Cu" "B.Mask" "B.Paste")
			(net "GND")
		)
	)
	(footprint ""
		(layer "B.Cu")
		(at 110.744 -50.816002 90)
		(property "Reference" "C132"
			(at 0 0 90)
			(layer "B.SilkS")
			(hide yes)
			(effects
				(font
					(size 1.27 1.27)
				)
				(justify mirror)
			)
		)
		(property "Value" "SC1U10V2KX-1GP"
			(at -1.1811 -2.7051 90)
			(unlocked yes)
			(layer "B.Fab")
			(hide yes)
			(effects
				(font
					(size 1.016 1.016)
					(thickness 0.1524)
				)
				(justify mirror)
			)
		)
		(property "Device Type" "C402H22"
			(at -1.1811 -4.2291 90)
			(unlocked yes)
			(layer "B.Fab")
			(hide yes)
			(effects
				(font
					(size 1.016 1.016)
					(thickness 0.1524)
				)
				(justify mirror)
			)
		)
		(duplicate_pad_numbers_are_jumpers no)
		(fp_rect
			(start 0.381 0.7366)
			(end -0.381 -0.7366)
			(stroke
				(width 0)
				(type default)
			)
			(fill no)
			(layer "B.CrtYd")
		)
		(fp_rect
			(start 0.381 0.7366)
			(end -0.381 -0.7366)
			(stroke
				(width 0)
				(type default)
			)
			(fill no)
			(layer "B.Fab")
		)
		(pad "1" smd custom
			(at 0 -0.4572 270)
			(size 0.1143 0.1143)
			(layers "B.Cu" "B.Mask" "B.Paste")
			(net "PV_VDDR")
			(options
				(clearance outline)
				(anchor circle)
			)
			(primitives
				(gr_poly
					(pts
						(arc
							(start -0.254 0.1778)
							(mid -0.239121 0.213721)
							(end -0.2032 0.2286)
						)
						(arc
							(start 0.2032 0.2286)
							(mid 0.239121 0.213721)
							(end 0.254 0.1778)
						)
						(arc
							(start 0.254 -0.1778)
							(mid 0.239121 -0.213721)
							(end 0.2032 -0.2286)
						)
						(arc
							(start -0.2032 -0.2286)
							(mid -0.239121 -0.213721)
							(end -0.254 -0.1778)
						)
					)
					(width 0)
					(fill yes)
				)
			)
		)
		(pad "2" smd custom
			(at 0 0.4572 270)
			(size 0.1143 0.1143)
			(layers "B.Cu" "B.Mask" "B.Paste")
			(net "GND")
			(options
				(clearance outline)
				(anchor circle)
			)
			(primitives
				(gr_poly
					(pts
						(arc
							(start -0.254 0.1778)
							(mid -0.239121 0.213721)
							(end -0.2032 0.2286)
						)
						(arc
							(start 0.2032 0.2286)
							(mid 0.239121 0.213721)
							(end 0.254 0.1778)
						)
						(arc
							(start 0.254 -0.1778)
							(mid 0.239121 -0.213721)
							(end 0.2032 -0.2286)
						)
						(arc
							(start -0.2032 -0.2286)
							(mid -0.239121 -0.213721)
							(end -0.254 -0.1778)
						)
					)
					(width 0)
					(fill yes)
				)
			)
		)
	)
	(footprint ""
		(layer "B.Cu")
		(at 74.168 -44.196 90)
		(property "Reference" "R314"
			(at 0 0 90)
			(layer "B.SilkS")
			(hide yes)
			(effects
				(font
					(size 1.27 1.27)
				)
				(justify mirror)
			)
		)
		(property "Value" "10KR2F-2-GP"
			(at -0.064008 -3.993896 90)
			(unlocked yes)
			(layer "B.Fab")
			(hide yes)
			(effects
				(font
					(size 1.016 1.016)
					(thickness 0.1524)
				)
				(justify mirror)
			)
		)
		(property "Device Type" "R402H16"
			(at -0.064008 -5.517896 90)
			(unlocked yes)
			(layer "B.Fab")
			(hide yes)
			(effects
				(font
					(size 1.016 1.016)
					(thickness 0.1524)
				)
				(justify mirror)
			)
		)
		(duplicate_pad_numbers_are_jumpers no)
		(fp_rect
			(start 0.381 0.8382)
			(end -0.381 -0.8382)
			(stroke
				(width 0)
				(type default)
			)
			(fill no)
			(layer "B.CrtYd")
		)
		(fp_rect
			(start 0.381 0.8382)
			(end -0.381 -0.8382)
			(stroke
				(width 0)
				(type default)
			)
			(fill no)
			(layer "B.Fab")
		)
		(pad "1" smd custom
			(at 0 -0.4318 270)
			(size 0.127 0.127)
			(layers "B.Cu" "B.Mask" "B.Paste")
			(net "P3V3")
			(options
				(clearance outline)
				(anchor circle)
			)
			(primitives
				(gr_poly
					(pts
						(arc
							(start -0.2032 0.2794)
							(mid -0.239121 0.264521)
							(end -0.254 0.2286)
						)
						(arc
							(start -0.254 -0.2286)
							(mid -0.239121 -0.264521)
							(end -0.2032 -0.2794)
						)
						(arc
							(start 0.2032 -0.2794)
							(mid 0.239121 -0.264521)
							(end 0.254 -0.2286)
						)
						(arc
							(start 0.254 0.2286)
							(mid 0.239121 0.264521)
							(end 0.2032 0.2794)
						)
					)
					(width 0)
					(fill yes)
				)
			)
		)
		(pad "2" smd custom
			(at 0 0.4318 270)
			(size 0.127 0.127)
			(layers "B.Cu" "B.Mask" "B.Paste")
			(net "LPC_CPU_FRAME#")
			(options
				(clearance outline)
				(anchor circle)
			)
			(primitives
				(gr_poly
					(pts
						(arc
							(start -0.2032 0.2794)
							(mid -0.239121 0.264521)
							(end -0.254 0.2286)
						)
						(arc
							(start -0.254 -0.2286)
							(mid -0.239121 -0.264521)
							(end -0.2032 -0.2794)
						)
						(arc
							(start 0.2032 -0.2794)
							(mid 0.239121 -0.264521)
							(end 0.254 -0.2286)
						)
						(arc
							(start 0.254 0.2286)
							(mid 0.239121 0.264521)
							(end 0.2032 0.2794)
						)
					)
					(width 0)
					(fill yes)
				)
			)
		)
	)
	(footprint ""
		(layer "B.Cu")
		(at 76.708 -61.8744)
		(property "Reference" "C86"
			(at 0 0 0)
			(layer "B.SilkS")
			(hide yes)
			(effects
				(font
					(size 1.27 1.27)
				)
				(justify mirror)
			)
		)
		(property "Value" "SCD1U16V2KX-3GP"
			(at -1.1811 -2.7051 0)
			(unlocked yes)
			(layer "B.Fab")
			(hide yes)
			(effects
				(font
					(size 1.016 1.016)
					(thickness 0.1524)
				)
				(justify mirror)
			)
		)
		(property "Device Type" "C402H22"
			(at -1.1811 -4.2291 0)
			(unlocked yes)
			(layer "B.Fab")
			(hide yes)
			(effects
				(font
					(size 1.016 1.016)
					(thickness 0.1524)
				)
				(justify mirror)
			)
		)
		(duplicate_pad_numbers_are_jumpers no)
		(fp_rect
			(start 0.381 0.7366)
			(end -0.381 -0.7366)
			(stroke
				(width 0)
				(type default)
			)
			(fill no)
			(layer "B.CrtYd")
		)
		(fp_rect
			(start 0.381 0.7366)
			(end -0.381 -0.7366)
			(stroke
				(width 0)
				(type default)
			)
			(fill no)
			(layer "B.Fab")
		)
		(pad "1" smd custom
			(at 0 -0.4572 180)
			(size 0.1143 0.1143)
			(layers "B.Cu" "B.Mask" "B.Paste")
			(net "PVNN_SENSE")
			(options
				(clearance outline)
				(anchor circle)
			)
			(primitives
				(gr_poly
					(pts
						(arc
							(start -0.254 0.1778)
							(mid -0.239121 0.213721)
							(end -0.2032 0.2286)
						)
						(arc
							(start 0.2032 0.2286)
							(mid 0.239121 0.213721)
							(end 0.254 0.1778)
						)
						(arc
							(start 0.254 -0.1778)
							(mid 0.239121 -0.213721)
							(end 0.2032 -0.2286)
						)
						(arc
							(start -0.2032 -0.2286)
							(mid -0.239121 -0.213721)
							(end -0.254 -0.1778)
						)
					)
					(width 0)
					(fill yes)
				)
			)
		)
		(pad "2" smd custom
			(at 0 0.4572 180)
			(size 0.1143 0.1143)
			(layers "B.Cu" "B.Mask" "B.Paste")
			(net "GND")
			(options
				(clearance outline)
				(anchor circle)
			)
			(primitives
				(gr_poly
					(pts
						(arc
							(start -0.254 0.1778)
							(mid -0.239121 0.213721)
							(end -0.2032 0.2286)
						)
						(arc
							(start 0.2032 0.2286)
							(mid 0.239121 0.213721)
							(end 0.254 0.1778)
						)
						(arc
							(start 0.254 -0.1778)
							(mid 0.239121 -0.213721)
							(end 0.2032 -0.2286)
						)
						(arc
							(start -0.2032 -0.2286)
							(mid -0.239121 -0.213721)
							(end -0.254 -0.1778)
						)
					)
					(width 0)
					(fill yes)
				)
			)
		)
	)
	(footprint ""
		(layer "B.Cu")
		(at 96.06788 -43.69816)
		(property "Reference" "C124"
			(at 0 0 0)
			(layer "B.SilkS")
			(hide yes)
			(effects
				(font
					(size 1.27 1.27)
				)
				(justify mirror)
			)
		)
		(property "Value" "SC1U10V2KX-1GP"
			(at -1.1811 -2.7051 0)
			(unlocked yes)
			(layer "B.Fab")
			(hide yes)
			(effects
				(font
					(size 1.016 1.016)
					(thickness 0.1524)
				)
				(justify mirror)
			)
		)
		(property "Device Type" "C402H22"
			(at -1.1811 -4.2291 0)
			(unlocked yes)
			(layer "B.Fab")
			(hide yes)
			(effects
				(font
					(size 1.016 1.016)
					(thickness 0.1524)
				)
				(justify mirror)
			)
		)
		(duplicate_pad_numbers_are_jumpers no)
		(fp_rect
			(start 0.381 0.7366)
			(end -0.381 -0.7366)
			(stroke
				(width 0)
				(type default)
			)
			(fill no)
			(layer "B.CrtYd")
		)
		(fp_rect
			(start 0.381 0.7366)
			(end -0.381 -0.7366)
			(stroke
				(width 0)
				(type default)
			)
			(fill no)
			(layer "B.Fab")
		)
		(pad "1" smd custom
			(at 0 -0.4572 180)
			(size 0.1143 0.1143)
			(layers "B.Cu" "B.Mask" "B.Paste")
			(net "VCCA_PLLDDR0_AVN")
			(options
				(clearance outline)
				(anchor circle)
			)
			(primitives
				(gr_poly
					(pts
						(arc
							(start -0.254 0.1778)
							(mid -0.239121 0.213721)
							(end -0.2032 0.2286)
						)
						(arc
							(start 0.2032 0.2286)
							(mid 0.239121 0.213721)
							(end 0.254 0.1778)
						)
						(arc
							(start 0.254 -0.1778)
							(mid 0.239121 -0.213721)
							(end 0.2032 -0.2286)
						)
						(arc
							(start -0.2032 -0.2286)
							(mid -0.239121 -0.213721)
							(end -0.254 -0.1778)
						)
					)
					(width 0)
					(fill yes)
				)
			)
		)
		(pad "2" smd custom
			(at 0 0.4572 180)
			(size 0.1143 0.1143)
			(layers "B.Cu" "B.Mask" "B.Paste")
			(net "GND")
			(options
				(clearance outline)
				(anchor circle)
			)
			(primitives
				(gr_poly
					(pts
						(arc
							(start -0.254 0.1778)
							(mid -0.239121 0.213721)
							(end -0.2032 0.2286)
						)
						(arc
							(start 0.2032 0.2286)
							(mid 0.239121 0.213721)
							(end 0.254 0.1778)
						)
						(arc
							(start 0.254 -0.1778)
							(mid 0.239121 -0.213721)
							(end 0.2032 -0.2286)
						)
						(arc
							(start -0.2032 -0.2286)
							(mid -0.239121 -0.213721)
							(end -0.254 -0.1778)
						)
					)
					(width 0)
					(fill yes)
				)
			)
		)
	)
	(footprint ""
		(layer "B.Cu")
		(at 97.6376 -39.7256 180)
		(property "Reference" "TP30"
			(at 0 0 0)
			(layer "B.SilkS")
			(hide yes)
			(effects
				(font
					(size 1.27 1.27)
				)
				(justify mirror)
			)
		)
		(property "Value" "TPAD24"
			(at 0 -2.9972 180)
			(unlocked yes)
			(layer "B.Fab")
			(hide yes)
			(effects
				(font
					(size 1.016 1.016)
					(thickness 0.1524)
				)
				(justify mirror)
			)
		)
		(property "Device Type" "TPAD24"
			(at 0 -4.5212 180)
			(unlocked yes)
			(layer "B.Fab")
			(hide yes)
			(effects
				(font
					(size 1.016 1.016)
					(thickness 0.1524)
				)
				(justify mirror)
			)
		)
		(duplicate_pad_numbers_are_jumpers no)
		(fp_poly
			(pts
				(arc
					(start -0.3048 0)
					(mid 0.3048 0)
					(end -0.3048 0)
				)
			)
			(stroke
				(width 0)
				(type default)
			)
			(fill no)
			(layer "B.CrtYd")
		)
		(fp_poly
			(pts
				(arc
					(start -0.6096 0)
					(mid 0.6096 0)
					(end -0.6096 0)
				)
			)
			(stroke
				(width 0)
				(type default)
			)
			(fill no)
			(layer "B.Fab")
		)
		(pad "1" smd circle
			(at 0 0)
			(size 0.6096 0.6096)
			(layers "B.Cu" "B.Mask" "B.Paste")
			(net "VCCRAMCPUSI0GT_MOD3_1P03")
		)
	)
	(footprint ""
		(layer "B.Cu")
		(at 74.93 -50.673 -90)
		(property "Reference" "R38"
			(at 0 0 90)
			(layer "B.SilkS")
			(hide yes)
			(effects
				(font
					(size 1.27 1.27)
				)
				(justify mirror)
			)
		)
		(property "Value" "51R2F-2-GP"
			(at -0.064008 -3.993896 270)
			(unlocked yes)
			(layer "B.Fab")
			(hide yes)
			(effects
				(font
					(size 1.016 1.016)
					(thickness 0.1524)
				)
				(justify mirror)
			)
		)
		(property "Device Type" "R402H16"
			(at -0.064008 -5.517896 270)
			(unlocked yes)
			(layer "B.Fab")
			(hide yes)
			(effects
				(font
					(size 1.016 1.016)
					(thickness 0.1524)
				)
				(justify mirror)
			)
		)
		(duplicate_pad_numbers_are_jumpers no)
		(fp_rect
			(start 0.381 0.8382)
			(end -0.381 -0.8382)
			(stroke
				(width 0)
				(type default)
			)
			(fill no)
			(layer "B.CrtYd")
		)
		(fp_rect
			(start 0.381 0.8382)
			(end -0.381 -0.8382)
			(stroke
				(width 0)
				(type default)
			)
			(fill no)
			(layer "B.Fab")
		)
		(pad "1" smd custom
			(at 0 -0.4318 90)
			(size 0.127 0.127)
			(layers "B.Cu" "B.Mask" "B.Paste")
			(net "CTBTRIGOUT")
			(options
				(clearance outline)
				(anchor circle)
			)
			(primitives
				(gr_poly
					(pts
						(arc
							(start -0.2032 0.2794)
							(mid -0.239121 0.264521)
							(end -0.254 0.2286)
						)
						(arc
							(start -0.254 -0.2286)
							(mid -0.239121 -0.264521)
							(end -0.2032 -0.2794)
						)
						(arc
							(start 0.2032 -0.2794)
							(mid 0.239121 -0.264521)
							(end 0.254 -0.2286)
						)
						(arc
							(start 0.254 0.2286)
							(mid 0.239121 0.264521)
							(end 0.2032 0.2794)
						)
					)
					(width 0)
					(fill yes)
				)
			)
		)
		(pad "2" smd custom
			(at 0 0.4318 90)
			(size 0.127 0.127)
			(layers "B.Cu" "B.Mask" "B.Paste")
			(net "P1V0")
			(options
				(clearance outline)
				(anchor circle)
			)
			(primitives
				(gr_poly
					(pts
						(arc
							(start -0.2032 0.2794)
							(mid -0.239121 0.264521)
							(end -0.254 0.2286)
						)
						(arc
							(start -0.254 -0.2286)
							(mid -0.239121 -0.264521)
							(end -0.2032 -0.2794)
						)
						(arc
							(start 0.2032 -0.2794)
							(mid 0.239121 -0.264521)
							(end 0.254 -0.2286)
						)
						(arc
							(start 0.254 0.2286)
							(mid 0.239121 0.264521)
							(end 0.2032 0.2794)
						)
					)
					(width 0)
					(fill yes)
				)
			)
		)
	)
	(footprint ""
		(layer "B.Cu")
		(at 201.2696 -32.8422 90)
		(property "Reference" "LED6"
			(at 0 0 90)
			(layer "B.SilkS")
			(hide yes)
			(effects
				(font
					(size 1.27 1.27)
				)
				(justify mirror)
			)
		)
		(property "Value" "LED-YG-51-GP"
			(at 0.0381 -2.6162 90)
			(unlocked yes)
			(layer "B.Fab")
			(hide yes)
			(effects
				(font
					(size 1.016 1.016)
					(thickness 0.1524)
				)
				(justify mirror)
			)
		)
		(property "Device Type" "LED1608AKH40"
			(at 0.0381 -4.1402 90)
			(unlocked yes)
			(layer "B.Fab")
			(hide yes)
			(effects
				(font
					(size 1.016 1.016)
					(thickness 0.1524)
				)
				(justify mirror)
			)
		)
		(duplicate_pad_numbers_are_jumpers no)
		(fp_line
			(start 0.5334 1.3081)
			(end -0.5334 1.3081)
			(stroke
				(width 0.254)
				(type default)
			)
			(layer "B.SilkS")
		)
		(fp_rect
			(start 0.6604 1.1811)
			(end -0.6604 -1.1811)
			(stroke
				(width 0)
				(type default)
			)
			(fill no)
			(layer "B.CrtYd")
		)
		(fp_rect
			(start 0.6604 1.1811)
			(end -0.6604 -1.1811)
			(stroke
				(width 0)
				(type default)
			)
			(fill no)
			(layer "B.Fab")
		)
		(pad "A" smd rect
			(at 0 -0.652526 270)
			(size 1.0668 0.8128)
			(layers "B.Cu" "B.Mask" "B.Paste")
			(net "PORT80_R_BIT1")
		)
		(pad "K" smd rect
			(at 0 0.652526 270)
			(size 1.0668 0.8128)
			(layers "B.Cu" "B.Mask" "B.Paste")
			(net "PORT80_BIT1")
		)
	)
	(footprint ""
		(layer "B.Cu")
		(at 74.168 -41.656 90)
		(property "Reference" "R317"
			(at 0 0 90)
			(layer "B.SilkS")
			(hide yes)
			(effects
				(font
					(size 1.27 1.27)
				)
				(justify mirror)
			)
		)
		(property "Value" "1KR2F-3-GP"
			(at -0.064008 -3.993896 90)
			(unlocked yes)
			(layer "B.Fab")
			(hide yes)
			(effects
				(font
					(size 1.016 1.016)
					(thickness 0.1524)
				)
				(justify mirror)
			)
		)
		(property "Device Type" "R402H16"
			(at -0.064008 -5.517896 90)
			(unlocked yes)
			(layer "B.Fab")
			(hide yes)
			(effects
				(font
					(size 1.016 1.016)
					(thickness 0.1524)
				)
				(justify mirror)
			)
		)
		(duplicate_pad_numbers_are_jumpers no)
		(fp_rect
			(start 0.381 0.8382)
			(end -0.381 -0.8382)
			(stroke
				(width 0)
				(type default)
			)
			(fill no)
			(layer "B.CrtYd")
		)
		(fp_rect
			(start 0.381 0.8382)
			(end -0.381 -0.8382)
			(stroke
				(width 0)
				(type default)
			)
			(fill no)
			(layer "B.Fab")
		)
		(pad "1" smd custom
			(at 0 -0.4318 270)
			(size 0.127 0.127)
			(layers "B.Cu" "B.Mask" "B.Paste")
			(net "BD_ID_1")
			(options
				(clearance outline)
				(anchor circle)
			)
			(primitives
				(gr_poly
					(pts
						(arc
							(start -0.2032 0.2794)
							(mid -0.239121 0.264521)
							(end -0.254 0.2286)
						)
						(arc
							(start -0.254 -0.2286)
							(mid -0.239121 -0.264521)
							(end -0.2032 -0.2794)
						)
						(arc
							(start 0.2032 -0.2794)
							(mid 0.239121 -0.264521)
							(end 0.254 -0.2286)
						)
						(arc
							(start 0.254 0.2286)
							(mid 0.239121 0.264521)
							(end 0.2032 0.2794)
						)
					)
					(width 0)
					(fill yes)
				)
			)
		)
		(pad "2" smd custom
			(at 0 0.4318 270)
			(size 0.127 0.127)
			(layers "B.Cu" "B.Mask" "B.Paste")
			(net "GND")
			(options
				(clearance outline)
				(anchor circle)
			)
			(primitives
				(gr_poly
					(pts
						(arc
							(start -0.2032 0.2794)
							(mid -0.239121 0.264521)
							(end -0.254 0.2286)
						)
						(arc
							(start -0.254 -0.2286)
							(mid -0.239121 -0.264521)
							(end -0.2032 -0.2794)
						)
						(arc
							(start 0.2032 -0.2794)
							(mid 0.239121 -0.264521)
							(end 0.254 -0.2286)
						)
						(arc
							(start 0.254 0.2286)
							(mid 0.239121 0.264521)
							(end 0.2032 0.2794)
						)
					)
					(width 0)
					(fill yes)
				)
			)
		)
	)
)
